(kicad_pcb
	(version 20260206)
	(generator "pcbnew")
	(generator_version "10.0")
	(general
		(thickness 1.6)
		(legacy_teardrops no)
	)
	(paper "A4")
	(title_block
		(title "01162023_DA0F0TEBIF0_F0T_Expander_BD_F_brd_V02_OCP.brd")
		(comment 1 "Grand Teton / footprints 499-505 of 9728")
	)
	(layers
		(0 "F.Cu" signal "TOP")
		(4 "In1.Cu" signal "GND")
		(6 "In2.Cu" signal "VCC")
		(8 "In3.Cu" signal "VCC1")
		(10 "In4.Cu" signal "GND1")
		(12 "In5.Cu" signal "IN1")
		(14 "In6.Cu" signal "GND2")
		(16 "In7.Cu" signal "IN2")
		(18 "In8.Cu" signal "GND3")
		(20 "In9.Cu" signal "IN3")
		(22 "In10.Cu" signal "GND4")
		(24 "In11.Cu" signal "IN4")
		(26 "In12.Cu" signal "GND5")
		(28 "In13.Cu" signal "IN5")
		(30 "In14.Cu" signal "GND6")
		(32 "In15.Cu" signal "IN6")
		(34 "In16.Cu" signal "GND7")
		(2 "B.Cu" signal "BOTTOM")
		(9 "F.Adhes" user "F.Adhesive")
		(11 "B.Adhes" user "B.Adhesive")
		(13 "F.Paste" user "Package Geometry/Pastemask Top")
		(15 "B.Paste" user "Package Geometry/Pastemask Bottom")
		(5 "F.SilkS" user "Ref Des/Silkscreen Top")
		(7 "B.SilkS" user "Ref Des/Silkscreen Bottom")
		(1 "F.Mask" user "Board Geometry/Soldermask Top")
		(3 "B.Mask" user "Board Geometry/Soldermask Bottom")
		(17 "Dwgs.User" user "User.Drawings")
		(19 "Cmts.User" user "User.Comments")
		(21 "Eco1.User" user "User.Eco1")
		(23 "Eco2.User" user "User.Eco2")
		(25 "Edge.Cuts" user "Board Geometry/Outline")
		(27 "Margin" user)
		(31 "F.CrtYd" user "Package Geometry/Place Bound Top")
		(29 "B.CrtYd" user "Package Geometry/Place Bound Bottom")
		(35 "F.Fab" user "Ref Des/Assembly Top")
		(33 "B.Fab" user "Ref Des/Assembly Bottom")
	)
	(footprint ""
		(layer "F.Cu")
		(at 125.186948 -343.952322 90)
		(property "Reference" "C351"
			(at 0 0 90)
			(layer "F.SilkS")
			(hide yes)
			(effects
				(font
					(size 1.27 1.27)
				)
			)
		)
		(property "Value" ""
			(at 0 0 90)
			(layer "F.Fab")
			(effects
				(font
					(size 1.27 1.27)
				)
			)
		)
		(duplicate_pad_numbers_are_jumpers no)
		(fp_line
			(start 0.299974 -0.150114)
			(end 0.299974 0.150114)
			(stroke
				(width 0.1)
				(type default)
			)
			(layer "F.Fab")
		)
		(fp_line
			(start -0.299974 -0.150114)
			(end 0.299974 -0.150114)
			(stroke
				(width 0.1)
				(type default)
			)
			(layer "F.Fab")
		)
		(fp_line
			(start 0.299974 0.150114)
			(end -0.299974 0.150114)
			(stroke
				(width 0.1)
				(type default)
			)
			(layer "F.Fab")
		)
		(fp_line
			(start -0.299974 0.150114)
			(end -0.299974 -0.150114)
			(stroke
				(width 0.1)
				(type default)
			)
			(layer "F.Fab")
		)
		(pad "1" smd rect
			(at -0.2667 0 90)
			(size 0.3048 0.381)
			(layers "F.Cu" "F.Mask" "F.Paste")
			(net "P5E_PEX1_STN6_TX_DN<106>")
		)
		(pad "2" smd rect
			(at 0.2667 0 90)
			(size 0.3048 0.381)
			(layers "F.Cu" "F.Mask" "F.Paste")
			(net "P5E_PEX1_STN6_TX_C_DN<106>")
		)
	)
	(footprint ""
		(layer "F.Cu")
		(at 384.938524 -108.29544)
		(property "Reference" "C686"
			(at 0 0 0)
			(layer "F.SilkS")
			(hide yes)
			(effects
				(font
					(size 1.27 1.27)
				)
			)
		)
		(property "Value" ""
			(at 0 0 0)
			(layer "F.Fab")
			(effects
				(font
					(size 1.27 1.27)
				)
			)
		)
		(duplicate_pad_numbers_are_jumpers no)
		(fp_line
			(start -0.299974 -0.150114)
			(end 0.299974 -0.150114)
			(stroke
				(width 0.1)
				(type default)
			)
			(layer "F.Fab")
		)
		(fp_line
			(start -0.299974 0.150114)
			(end -0.299974 -0.150114)
			(stroke
				(width 0.1)
				(type default)
			)
			(layer "F.Fab")
		)
		(fp_line
			(start 0.299974 -0.150114)
			(end 0.299974 0.150114)
			(stroke
				(width 0.1)
				(type default)
			)
			(layer "F.Fab")
		)
		(fp_line
			(start 0.299974 0.150114)
			(end -0.299974 0.150114)
			(stroke
				(width 0.1)
				(type default)
			)
			(layer "F.Fab")
		)
		(pad "1" smd rect
			(at -0.2667 0)
			(size 0.3048 0.381)
			(layers "F.Cu" "F.Mask" "F.Paste")
			(net "P5E_PEX3_STN1_TX_DN<21>")
		)
		(pad "2" smd rect
			(at 0.2667 0)
			(size 0.3048 0.381)
			(layers "F.Cu" "F.Mask" "F.Paste")
			(net "P5E_PEX3_STN1_TX_C_DN<21>")
		)
	)
	(footprint ""
		(layer "F.Cu")
		(at 136.32561 -255.986534 -90)
		(property "Reference" "R6154"
			(at 0 0 270)
			(layer "F.SilkS")
			(hide yes)
			(effects
				(font
					(size 1.27 1.27)
				)
			)
		)
		(property "Value" ""
			(at 0 0 270)
			(layer "F.Fab")
			(effects
				(font
					(size 1.27 1.27)
				)
			)
		)
		(duplicate_pad_numbers_are_jumpers no)
		(fp_line
			(start -0.7874 0.4064)
			(end -0.7874 -0.4064)
			(stroke
				(width 0.1524)
				(type default)
			)
			(layer "F.SilkS")
		)
		(fp_line
			(start 0.7874 0.4064)
			(end -0.7874 0.4064)
			(stroke
				(width 0.1524)
				(type default)
			)
			(layer "F.SilkS")
		)
		(fp_line
			(start -0.7874 -0.4064)
			(end 0.7874 -0.4064)
			(stroke
				(width 0.1524)
				(type default)
			)
			(layer "F.SilkS")
		)
		(fp_line
			(start 0.7874 -0.4064)
			(end 0.7874 0.4064)
			(stroke
				(width 0.1524)
				(type default)
			)
			(layer "F.SilkS")
		)
		(fp_line
			(start -0.67945 0.3048)
			(end -0.67945 -0.305054)
			(stroke
				(width 0.1)
				(type default)
			)
			(layer "F.Fab")
		)
		(fp_line
			(start -0.12065 0.3048)
			(end -0.67945 0.3048)
			(stroke
				(width 0.1)
				(type default)
			)
			(layer "F.Fab")
		)
		(fp_line
			(start 0.120396 0.3048)
			(end 0.120396 0.2794)
			(stroke
				(width 0.1)
				(type default)
			)
			(layer "F.Fab")
		)
		(fp_line
			(start 0.67945 0.3048)
			(end 0.120396 0.3048)
			(stroke
				(width 0.1)
				(type default)
			)
			(layer "F.Fab")
		)
		(fp_line
			(start -0.12065 0.2794)
			(end -0.12065 0.3048)
			(stroke
				(width 0.1)
				(type default)
			)
			(layer "F.Fab")
		)
		(fp_line
			(start 0.120396 0.2794)
			(end -0.12065 0.2794)
			(stroke
				(width 0.1)
				(type default)
			)
			(layer "F.Fab")
		)
		(fp_line
			(start -0.12065 -0.2794)
			(end 0.12065 -0.2794)
			(stroke
				(width 0.1)
				(type default)
			)
			(layer "F.Fab")
		)
		(fp_line
			(start 0.12065 -0.2794)
			(end 0.12065 -0.3048)
			(stroke
				(width 0.1)
				(type default)
			)
			(layer "F.Fab")
		)
		(fp_line
			(start 0.12065 -0.3048)
			(end 0.67945 -0.3048)
			(stroke
				(width 0.1)
				(type default)
			)
			(layer "F.Fab")
		)
		(fp_line
			(start 0.67945 -0.3048)
			(end 0.67945 0.3048)
			(stroke
				(width 0.1)
				(type default)
			)
			(layer "F.Fab")
		)
		(fp_line
			(start -0.67945 -0.305054)
			(end -0.12065 -0.305054)
			(stroke
				(width 0.1)
				(type default)
			)
			(layer "F.Fab")
		)
		(fp_line
			(start -0.12065 -0.305054)
			(end -0.12065 -0.2794)
			(stroke
				(width 0.1)
				(type default)
			)
			(layer "F.Fab")
		)
		(pad "1" smd circle
			(at -0.40005 0 270)
			(size 0 0)
			(layers "F.Cu" "F.Mask" "F.Paste")
			(net "PEX1_SYS_ERR_R_N")
		)
		(pad "2" smd circle
			(at 0.40005 0 270)
			(size 0 0)
			(layers "F.Cu" "F.Mask" "F.Paste")
			(net "P1V8_PEX")
		)
	)
	(footprint ""
		(layer "F.Cu")
		(at 139.60221 -254.850646 180)
		(property "Reference" "D2"
			(at 1.221232 -1.72466 0)
			(unlocked yes)
			(layer "F.SilkS")
			(effects
				(font
					(size 0.7874 0.5842)
					(thickness 0.1524)
				)
				(justify left)
			)
		)
		(property "Value" ""
			(at 0 0 180)
			(layer "F.Fab")
			(effects
				(font
					(size 1.27 1.27)
				)
			)
		)
		(duplicate_pad_numbers_are_jumpers no)
		(fp_line
			(start 1.16078 0.4826)
			(end -0.64008 0.4826)
			(stroke
				(width 0.1524)
				(type default)
			)
			(layer "F.SilkS")
		)
		(fp_line
			(start 1.16078 -0.4826)
			(end 1.16078 0.4826)
			(stroke
				(width 0.1524)
				(type default)
			)
			(layer "F.SilkS")
		)
		(fp_line
			(start 1.03378 0.4826)
			(end -0.79248 0.4826)
			(stroke
				(width 0.1524)
				(type default)
			)
			(layer "F.SilkS")
		)
		(fp_line
			(start 1.03378 -0.4826)
			(end 1.03378 0.4826)
			(stroke
				(width 0.1524)
				(type default)
			)
			(layer "F.SilkS")
		)
		(fp_line
			(start 0.90678 0.4826)
			(end -0.90678 0.4826)
			(stroke
				(width 0.1524)
				(type default)
			)
			(layer "F.SilkS")
		)
		(fp_line
			(start 0.90678 -0.4826)
			(end 0.90678 0.4826)
			(stroke
				(width 0.1524)
				(type default)
			)
			(layer "F.SilkS")
		)
		(fp_line
			(start -0.64008 -0.4826)
			(end 1.16078 -0.4826)
			(stroke
				(width 0.1524)
				(type default)
			)
			(layer "F.SilkS")
		)
		(fp_line
			(start -0.79248 -0.4826)
			(end 1.03378 -0.4826)
			(stroke
				(width 0.1524)
				(type default)
			)
			(layer "F.SilkS")
		)
		(fp_line
			(start -0.89408 -0.4826)
			(end 0.90678 -0.4826)
			(stroke
				(width 0.1524)
				(type default)
			)
			(layer "F.SilkS")
		)
		(fp_line
			(start -0.90678 0.4826)
			(end -0.90678 -0.4699)
			(stroke
				(width 0.1524)
				(type default)
			)
			(layer "F.SilkS")
		)
		(fp_line
			(start 0.499872 0.249936)
			(end -0.499872 0.249936)
			(stroke
				(width 0.1)
				(type default)
			)
			(layer "F.Fab")
		)
		(fp_line
			(start 0.499872 -0.249936)
			(end 0.499872 0.249936)
			(stroke
				(width 0.1)
				(type default)
			)
			(layer "F.Fab")
		)
		(fp_line
			(start -0.499872 0.249936)
			(end -0.499872 -0.249936)
			(stroke
				(width 0.1)
				(type default)
			)
			(layer "F.Fab")
		)
		(fp_line
			(start -0.499872 -0.249936)
			(end 0.499872 -0.249936)
			(stroke
				(width 0.1)
				(type default)
			)
			(layer "F.Fab")
		)
		(pad "A" smd rect
			(at -0.47498 0 180)
			(size 0.6096 0.7112)
			(layers "F.Cu" "F.Mask" "F.Paste")
			(net "LED_PEX1_SYS_ERR_N")
		)
		(pad "C" smd rect
			(at 0.47498 0 180)
			(size 0.6096 0.7112)
			(layers "F.Cu" "F.Mask" "F.Paste")
			(net "PEX1_SYS_ERR_3V3_N")
		)
	)
	(footprint ""
		(layer "F.Cu")
		(at 336.764884 -114.833654 -90)
		(property "Reference" "PC812"
			(at 0 0 270)
			(layer "F.SilkS")
			(hide yes)
			(effects
				(font
					(size 1.27 1.27)
				)
			)
		)
		(property "Value" ""
			(at 0 0 270)
			(layer "F.Fab")
			(effects
				(font
					(size 1.27 1.27)
				)
			)
		)
		(duplicate_pad_numbers_are_jumpers no)
		(fp_line
			(start -1.2954 0.5842)
			(end -1.2954 -0.5842)
			(stroke
				(width 0.1524)
				(type default)
			)
			(layer "F.SilkS")
		)
		(fp_line
			(start 1.2954 0.5842)
			(end -1.2954 0.5842)
			(stroke
				(width 0.1524)
				(type default)
			)
			(layer "F.SilkS")
		)
		(fp_line
			(start -1.2954 -0.5842)
			(end 1.2954 -0.5842)
			(stroke
				(width 0.1524)
				(type default)
			)
			(layer "F.SilkS")
		)
		(fp_line
			(start 1.2954 -0.5842)
			(end 1.2954 0.5842)
			(stroke
				(width 0.1524)
				(type default)
			)
			(layer "F.SilkS")
		)
		(fp_line
			(start -0.8636 0.4572)
			(end -0.8636 0.4064)
			(stroke
				(width 0.1)
				(type default)
			)
			(layer "F.Fab")
		)
		(fp_line
			(start 0.8636 0.4572)
			(end -0.8636 0.4572)
			(stroke
				(width 0.1)
				(type default)
			)
			(layer "F.Fab")
		)
		(fp_line
			(start -1.1938 0.4064)
			(end -1.1938 -0.4064)
			(stroke
				(width 0.1)
				(type default)
			)
			(layer "F.Fab")
		)
		(fp_line
			(start -0.8636 0.4064)
			(end -1.1938 0.4064)
			(stroke
				(width 0.1)
				(type default)
			)
			(layer "F.Fab")
		)
		(fp_line
			(start 0.8636 0.4064)
			(end 0.8636 0.4572)
			(stroke
				(width 0.1)
				(type default)
			)
			(layer "F.Fab")
		)
		(fp_line
			(start 1.1938 0.4064)
			(end 0.8636 0.4064)
			(stroke
				(width 0.1)
				(type default)
			)
			(layer "F.Fab")
		)
		(fp_line
			(start -1.1938 -0.4064)
			(end -0.8636 -0.4064)
			(stroke
				(width 0.1)
				(type default)
			)
			(layer "F.Fab")
		)
		(fp_line
			(start -0.8636 -0.4064)
			(end -0.8636 -0.4572)
			(stroke
				(width 0.1)
				(type default)
			)
			(layer "F.Fab")
		)
		(fp_line
			(start 0.8636 -0.4064)
			(end 1.1938 -0.4064)
			(stroke
				(width 0.1)
				(type default)
			)
			(layer "F.Fab")
		)
		(fp_line
			(start 1.1938 -0.4064)
			(end 1.1938 0.4064)
			(stroke
				(width 0.1)
				(type default)
			)
			(layer "F.Fab")
		)
		(fp_line
			(start -0.8636 -0.4572)
			(end 0.8636 -0.4572)
			(stroke
				(width 0.1)
				(type default)
			)
			(layer "F.Fab")
		)
		(fp_line
			(start 0.8636 -0.4572)
			(end 0.8636 -0.4064)
			(stroke
				(width 0.1)
				(type default)
			)
			(layer "F.Fab")
		)
		(pad "1" smd rect
			(at -0.7366 0 180)
			(size 0.7112 0.8128)
			(layers "F.Cu" "F.Mask" "F.Paste")
			(net "GND")
		)
		(pad "2" smd rect
			(at 0.7366 0 180)
			(size 0.7112 0.8128)
			(layers "F.Cu" "F.Mask" "F.Paste")
			(net "P12V_NIC5_CO_AVIN_PD")
		)
	)
	(footprint ""
		(layer "F.Cu")
		(at 23.624794 -259.378958)
		(property "Reference" "R1261"
			(at 0 0 0)
			(layer "F.SilkS")
			(hide yes)
			(effects
				(font
					(size 1.27 1.27)
				)
			)
		)
		(property "Value" ""
			(at 0 0 0)
			(layer "F.Fab")
			(effects
				(font
					(size 1.27 1.27)
				)
			)
		)
		(duplicate_pad_numbers_are_jumpers no)
		(fp_line
			(start -0.7874 -0.4064)
			(end 0.7874 -0.4064)
			(stroke
				(width 0.1524)
				(type default)
			)
			(layer "F.SilkS")
		)
		(fp_line
			(start -0.7874 0.4064)
			(end -0.7874 -0.4064)
			(stroke
				(width 0.1524)
				(type default)
			)
			(layer "F.SilkS")
		)
		(fp_line
			(start 0.7874 -0.4064)
			(end 0.7874 0.4064)
			(stroke
				(width 0.1524)
				(type default)
			)
			(layer "F.SilkS")
		)
		(fp_line
			(start 0.7874 0.4064)
			(end -0.7874 0.4064)
			(stroke
				(width 0.1524)
				(type default)
			)
			(layer "F.SilkS")
		)
		(fp_line
			(start -0.67945 -0.305054)
			(end -0.12065 -0.305054)
			(stroke
				(width 0.1)
				(type default)
			)
			(layer "F.Fab")
		)
		(fp_line
			(start -0.67945 0.3048)
			(end -0.67945 -0.305054)
			(stroke
				(width 0.1)
				(type default)
			)
			(layer "F.Fab")
		)
		(fp_line
			(start -0.12065 -0.305054)
			(end -0.12065 -0.2794)
			(stroke
				(width 0.1)
				(type default)
			)
			(layer "F.Fab")
		)
		(fp_line
			(start -0.12065 -0.2794)
			(end 0.12065 -0.2794)
			(stroke
				(width 0.1)
				(type default)
			)
			(layer "F.Fab")
		)
		(fp_line
			(start -0.12065 0.2794)
			(end -0.12065 0.3048)
			(stroke
				(width 0.1)
				(type default)
			)
			(layer "F.Fab")
		)
		(fp_line
			(start -0.12065 0.3048)
			(end -0.67945 0.3048)
			(stroke
				(width 0.1)
				(type default)
			)
			(layer "F.Fab")
		)
		(fp_line
			(start 0.120396 0.2794)
			(end -0.12065 0.2794)
			(stroke
				(width 0.1)
				(type default)
			)
			(layer "F.Fab")
		)
		(fp_line
			(start 0.120396 0.3048)
			(end 0.120396 0.2794)
			(stroke
				(width 0.1)
				(type default)
			)
			(layer "F.Fab")
		)
		(fp_line
			(start 0.12065 -0.3048)
			(end 0.67945 -0.3048)
			(stroke
				(width 0.1)
				(type default)
			)
			(layer "F.Fab")
		)
		(fp_line
			(start 0.12065 -0.2794)
			(end 0.12065 -0.3048)
			(stroke
				(width 0.1)
				(type default)
			)
			(layer "F.Fab")
		)
		(fp_line
			(start 0.67945 -0.3048)
			(end 0.67945 0.3048)
			(stroke
				(width 0.1)
				(type default)
			)
			(layer "F.Fab")
		)
		(fp_line
			(start 0.67945 0.3048)
			(end 0.120396 0.3048)
			(stroke
				(width 0.1)
				(type default)
			)
			(layer "F.Fab")
		)
		(pad "1" smd circle
			(at -0.40005 0)
			(size 0 0)
			(layers "F.Cu" "F.Mask" "F.Paste")
			(net "PEX0_SYS_ERR_N_G")
		)
		(pad "2" smd circle
			(at 0.40005 0)
			(size 0 0)
			(layers "F.Cu" "F.Mask" "F.Paste")
			(net "P3V3_AUX")
		)
	)
	(footprint ""
		(layer "F.Cu")
		(at 15.804896 -119.140986 -90)
		(property "Reference" "R5855"
			(at 0 0 270)
			(layer "F.SilkS")
			(hide yes)
			(effects
				(font
					(size 1.27 1.27)
				)
			)
		)
		(property "Value" ""
			(at 0 0 270)
			(layer "F.Fab")
			(effects
				(font
					(size 1.27 1.27)
				)
			)
		)
		(duplicate_pad_numbers_are_jumpers no)
		(fp_line
			(start -0.7874 0.4064)
			(end -0.7874 -0.4064)
			(stroke
				(width 0.1524)
				(type default)
			)
			(layer "F.SilkS")
		)
		(fp_line
			(start 0.7874 0.4064)
			(end -0.7874 0.4064)
			(stroke
				(width 0.1524)
				(type default)
			)
			(layer "F.SilkS")
		)
		(fp_line
			(start -0.7874 -0.4064)
			(end 0.7874 -0.4064)
			(stroke
				(width 0.1524)
				(type default)
			)
			(layer "F.SilkS")
		)
		(fp_line
			(start 0.7874 -0.4064)
			(end 0.7874 0.4064)
			(stroke
				(width 0.1524)
				(type default)
			)
			(layer "F.SilkS")
		)
		(fp_line
			(start -0.67945 0.3048)
			(end -0.67945 -0.305054)
			(stroke
				(width 0.1)
				(type default)
			)
			(layer "F.Fab")
		)
		(fp_line
			(start -0.12065 0.3048)
			(end -0.67945 0.3048)
			(stroke
				(width 0.1)
				(type default)
			)
			(layer "F.Fab")
		)
		(fp_line
			(start 0.120396 0.3048)
			(end 0.120396 0.2794)
			(stroke
				(width 0.1)
				(type default)
			)
			(layer "F.Fab")
		)
		(fp_line
			(start 0.67945 0.3048)
			(end 0.120396 0.3048)
			(stroke
				(width 0.1)
				(type default)
			)
			(layer "F.Fab")
		)
		(fp_line
			(start -0.12065 0.2794)
			(end -0.12065 0.3048)
			(stroke
				(width 0.1)
				(type default)
			)
			(layer "F.Fab")
		)
		(fp_line
			(start 0.120396 0.2794)
			(end -0.12065 0.2794)
			(stroke
				(width 0.1)
				(type default)
			)
			(layer "F.Fab")
		)
		(fp_line
			(start -0.12065 -0.2794)
			(end 0.12065 -0.2794)
			(stroke
				(width 0.1)
				(type default)
			)
			(layer "F.Fab")
		)
		(fp_line
			(start 0.12065 -0.2794)
			(end 0.12065 -0.3048)
			(stroke
				(width 0.1)
				(type default)
			)
			(layer "F.Fab")
		)
		(fp_line
			(start 0.12065 -0.3048)
			(end 0.67945 -0.3048)
			(stroke
				(width 0.1)
				(type default)
			)
			(layer "F.Fab")
		)
		(fp_line
			(start 0.67945 -0.3048)
			(end 0.67945 0.3048)
			(stroke
				(width 0.1)
				(type default)
			)
			(layer "F.Fab")
		)
		(fp_line
			(start -0.67945 -0.305054)
			(end -0.12065 -0.305054)
			(stroke
				(width 0.1)
				(type default)
			)
			(layer "F.Fab")
		)
		(fp_line
			(start -0.12065 -0.305054)
			(end -0.12065 -0.2794)
			(stroke
				(width 0.1)
				(type default)
			)
			(layer "F.Fab")
		)
		(pad "1" smd circle
			(at -0.40005 0 270)
			(size 0 0)
			(layers "F.Cu" "F.Mask" "F.Paste")
			(net "HP_NIC0_EN")
		)
		(pad "2" smd circle
			(at 0.40005 0 270)
			(size 0 0)
			(layers "F.Cu" "F.Mask" "F.Paste")
			(net "P3V3_NIC0_CO_EN")
		)
	)
)
